#ISCELL
  logical_power design_note *
  *
#ISCELL
  mstr_misc dns *
  *
#ISCELL
  pure_quanta quanta_title_block_c *
  *
#ISCELL
  standard offpage *
  page32_i100
#ISCELL
  standard offpage *
  page32_i101
#ISCELL
  standard offpage *
  page32_i102
#CELL
  pure_quanta q_res *
  page32_i103
#CELL
  pure_quanta q_res *
  page32_i104
#CELL
  pure_quanta q_res *
  page32_i105
#CELL
  pure_quanta q_res *
  page32_i106
#CELL
  pure_quanta q_res *
  page32_i107
#ISCELL
  logical_power universal_power *
  page32_i108
#ISCELL
  standard offpage *
  page32_i109
#ISCELL
  standard offpage *
  page32_i110
#ISCELL
  standard offpage *
  page32_i111
#ISCELL
  standard offpage *
  page32_i112
#ISCELL
  logical_power universal_gnd *
  page32_i113
#CELL
  pure_quanta q_res *
  page32_i117
#ISCELL
  logical_power universal_power *
  page32_i118
#CELL
  pure_quanta q_res *
  page32_i119
#CELL
  pure_quanta q_res *
  page32_i120
#ISCELL
  logical_power universal_gnd *
  page32_i123
#ISCELL
  standard offpage *
  page32_i124
#CELL
  pure_quanta q_res *
  page32_i126
#CELL
  pure_quanta q_res *
  page32_i127
#CELL
  pure_quanta q_res *
  page32_i128
#CELL
  pure_quanta q_res *
  page32_i129
#CELL
  pure_quanta q_res *
  page32_i131
#CELL
  pure_quanta conn8_210hp1080br1 *
  page32_i132
#CELL
  pure_quanta q_res *
  page32_i140
#CELL
  pure_quanta q_res *
  page32_i141
#ISCELL
  logical_power universal_gnd *
  page32_i142
#CELL
  pure_quanta q_res *
  page32_i143
#CELL
  pure_quanta schottky_12 *
  page32_i144
#ISCELL
  logical_power universal_gnd *
  page32_i145
#ISCELL
  standard offpage *
  page32_i17
#ISCELL
  logical_power universal_gnd *
  page32_i19
#ISCELL
  logical_power universal_power *
  page32_i20
#CELL
  pure_quanta q_cap *
  page32_i21
#CELL
  pure_quanta q_cap *
  page32_i22
#CELL
  pure_quanta q_res *
  page32_i23
#ISCELL
  standard offpage *
  page32_i41
#ISCELL
  standard offpage *
  page32_i42
#ISCELL
  standard offpage *
  page32_i43
#ISCELL
  standard offpage *
  page32_i44
#ISCELL
  standard offpage *
  page32_i45
#ISCELL
  standard offpage *
  page32_i49
#ISCELL
  standard offpage *
  page32_i50
#ISCELL
  standard offpage *
  page32_i51
#ISCELL
  standard offpage *
  page32_i54
#ISCELL
  standard offpage *
  page32_i55
#ISCELL
  standard offpage *
  page32_i56
#ISCELL
  standard offpage *
  page32_i57
#ISCELL
  standard offpage *
  page32_i74
#ISCELL
  standard offpage *
  page32_i75
#ISCELL
  standard offpage *
  page32_i76
#ISCELL
  standard offpage *
  page32_i77
#CELL
  pure_quanta q_res *
  page32_i78
#CELL
  pure_quanta q_res *
  page32_i80
#CELL
  pure_quanta q_res *
  page32_i81
#ISCELL
  standard offpage *
  page32_i82
#ISCELL
  standard offpage *
  page32_i83
#ISCELL
  standard offpage *
  page32_i84
#ISCELL
  standard offpage *
  page32_i85
#ISCELL
  standard offpage *
  page32_i86
#CELL
  pure_quanta q_res *
  page32_i87
#CELL
  pure_quanta q_res *
  page32_i88
#ISCELL
  standard offpage *
  page32_i89
#ISCELL
  standard offpage *
  page32_i90
#ISCELL
  standard offpage *
  page32_i91
#ISCELL
  standard offpage *
  page32_i92
#ISCELL
  standard offpage *
  page32_i93
#CELL
  pure_quanta q_res *
  page32_i94
#CELL
  pure_quanta q_res *
  page32_i95
#CELL
  pure_quanta q_res *
  page32_i96
#CELL
  pure_quanta q_res *
  page32_i97
#ISCELL
  standard offpage *
  page32_i98
#ISCELL
  standard offpage *
  page32_i99
